# S9S_MB_2U (Grand Teton) — schematic netlist excerpt (pin names and nets, part order shuffled) for the footprints in the layout excerpt that follows; sources: Cadence DE-HDL packaged netlist, KiCad conversion of 03242023_DA0F0TMBIJ0_F0T_Motherboard_J_brd_V01_OCP.brd

R3708  Q_RES  10K 1% EMPTY  pkg 0402LF  page 233 : A = P3V3_AUX ; B = PCA9548_PCIE0_ADDR0
R3718  Q_RES  0 5% CHIP  pkg 0402LF  page 233 : A = SMB_LM75_1_3V3AUX_SDA_R ; B = SMB_LM75_1_3V3AUX_SDA

(kicad_pcb
	(version 20260206)
	(generator "pcbnew")
	(generator_version "10.0")
	(general
		(thickness 1.6)
		(legacy_teardrops no)
	)
	(paper "A4")
	(title_block
		(title "03242023_DA0F0TMBIJ0_F0T_Motherboard_J_brd_V01_OCP.brd")
		(comment 1 "Grand Teton / footprints 722-723 of 6105")
	)
	(layers
		(0 "F.Cu" signal "TOP")
		(4 "In1.Cu" signal "GND")
		(6 "In2.Cu" signal "IN1")
		(8 "In3.Cu" signal "GND1")
		(10 "In4.Cu" signal "IN2")
		(12 "In5.Cu" signal "GND2")
		(14 "In6.Cu" signal "IN3")
		(16 "In7.Cu" signal "GND3")
		(18 "In8.Cu" signal "VCC")
		(20 "In9.Cu" signal "VCC1")
		(22 "In10.Cu" signal "GND4")
		(24 "In11.Cu" signal "IN4")
		(26 "In12.Cu" signal "GND5")
		(28 "In13.Cu" signal "IN5")
		(30 "In14.Cu" signal "GND6")
		(32 "In15.Cu" signal "IN6")
		(34 "In16.Cu" signal "GND7")
		(2 "B.Cu" signal "BOTTOM")
		(9 "F.Adhes" user "F.Adhesive")
		(11 "B.Adhes" user "B.Adhesive")
		(13 "F.Paste" user "Package Geometry/Pastemask Top")
		(15 "B.Paste" user "Package Geometry/Pastemask Bottom")
		(5 "F.SilkS" user "Ref Des/Silkscreen Top")
		(7 "B.SilkS" user "Ref Des/Silkscreen Bottom")
		(1 "F.Mask" user "Board Geometry/Soldermask Top")
		(3 "B.Mask" user "Board Geometry/Soldermask Bottom")
		(17 "Dwgs.User" user "User.Drawings")
		(19 "Cmts.User" user "User.Comments")
		(21 "Eco1.User" user "User.Eco1")
		(23 "Eco2.User" user "User.Eco2")
		(25 "Edge.Cuts" user "Board Geometry/Outline")
		(27 "Margin" user)
		(31 "F.CrtYd" user "Package Geometry/Place Bound Top")
		(29 "B.CrtYd" user "Package Geometry/Place Bound Bottom")
		(35 "F.Fab" user "Ref Des/Assembly Top")
		(33 "B.Fab" user "Ref Des/Assembly Bottom")
	)
	(footprint ""
		(layer "F.Cu")
		(at 54.242716 -109.91469 180)
		(property "Reference" "R3718"
			(at 0 0 180)
			(layer "F.SilkS")
			(hide yes)
			(effects
				(font
					(size 1.27 1.27)
				)
			)
		)
		(property "Value" ""
			(at 0 0 180)
			(layer "F.Fab")
			(effects
				(font
					(size 1.27 1.27)
				)
			)
		)
		(duplicate_pad_numbers_are_jumpers no)
		(fp_line
			(start 0.7874 0.4064)
			(end -0.7874 0.4064)
			(stroke
				(width 0.1524)
				(type default)
			)
			(layer "F.SilkS")
		)
		(fp_line
			(start 0.7874 -0.4064)
			(end 0.7874 0.4064)
			(stroke
				(width 0.1524)
				(type default)
			)
			(layer "F.SilkS")
		)
		(fp_line
			(start -0.7874 0.4064)
			(end -0.7874 -0.4064)
			(stroke
				(width 0.1524)
				(type default)
			)
			(layer "F.SilkS")
		)
		(fp_line
			(start -0.7874 -0.4064)
			(end 0.7874 -0.4064)
			(stroke
				(width 0.1524)
				(type default)
			)
			(layer "F.SilkS")
		)
		(fp_line
			(start 0.67945 0.3048)
			(end 0.120396 0.3048)
			(stroke
				(width 0.1)
				(type default)
			)
			(layer "F.Fab")
		)
		(fp_line
			(start 0.67945 -0.3048)
			(end 0.67945 0.3048)
			(stroke
				(width 0.1)
				(type default)
			)
			(layer "F.Fab")
		)
		(fp_line
			(start 0.12065 -0.2794)
			(end 0.12065 -0.3048)
			(stroke
				(width 0.1)
				(type default)
			)
			(layer "F.Fab")
		)
		(fp_line
			(start 0.12065 -0.3048)
			(end 0.67945 -0.3048)
			(stroke
				(width 0.1)
				(type default)
			)
			(layer "F.Fab")
		)
		(fp_line
			(start 0.120396 0.3048)
			(end 0.120396 0.2794)
			(stroke
				(width 0.1)
				(type default)
			)
			(layer "F.Fab")
		)
		(fp_line
			(start 0.120396 0.2794)
			(end -0.12065 0.2794)
			(stroke
				(width 0.1)
				(type default)
			)
			(layer "F.Fab")
		)
		(fp_line
			(start -0.12065 0.3048)
			(end -0.67945 0.3048)
			(stroke
				(width 0.1)
				(type default)
			)
			(layer "F.Fab")
		)
		(fp_line
			(start -0.12065 0.2794)
			(end -0.12065 0.3048)
			(stroke
				(width 0.1)
				(type default)
			)
			(layer "F.Fab")
		)
		(fp_line
			(start -0.12065 -0.2794)
			(end 0.12065 -0.2794)
			(stroke
				(width 0.1)
				(type default)
			)
			(layer "F.Fab")
		)
		(fp_line
			(start -0.12065 -0.305054)
			(end -0.12065 -0.2794)
			(stroke
				(width 0.1)
				(type default)
			)
			(layer "F.Fab")
		)
		(fp_line
			(start -0.67945 0.3048)
			(end -0.67945 -0.305054)
			(stroke
				(width 0.1)
				(type default)
			)
			(layer "F.Fab")
		)
		(fp_line
			(start -0.67945 -0.305054)
			(end -0.12065 -0.305054)
			(stroke
				(width 0.1)
				(type default)
			)
			(layer "F.Fab")
		)
		(pad "1" smd circle
			(at -0.40005 0 180)
			(size 0 0)
			(layers "F.Cu" "F.Mask" "F.Paste")
			(net "SMB_LM75_1_3V3AUX_SDA_R")
		)
		(pad "2" smd circle
			(at 0.40005 0 180)
			(size 0 0)
			(layers "F.Cu" "F.Mask" "F.Paste")
			(net "SMB_LM75_1_3V3AUX_SDA")
		)
	)
	(footprint ""
		(layer "F.Cu")
		(at 51.593496 -118.93677)
		(property "Reference" "R3708"
			(at 0 0 0)
			(layer "F.SilkS")
			(hide yes)
			(effects
				(font
					(size 1.27 1.27)
				)
			)
		)
		(property "Value" ""
			(at 0 0 0)
			(layer "F.Fab")
			(effects
				(font
					(size 1.27 1.27)
				)
			)
		)
		(duplicate_pad_numbers_are_jumpers no)
		(fp_line
			(start -0.7874 -0.4064)
			(end 0.7874 -0.4064)
			(stroke
				(width 0.1524)
				(type default)
			)
			(layer "F.SilkS")
		)
		(fp_line
			(start -0.7874 0.4064)
			(end -0.7874 -0.4064)
			(stroke
				(width 0.1524)
				(type default)
			)
			(layer "F.SilkS")
		)
		(fp_line
			(start 0.7874 -0.4064)
			(end 0.7874 0.4064)
			(stroke
				(width 0.1524)
				(type default)
			)
			(layer "F.SilkS")
		)
		(fp_line
			(start 0.7874 0.4064)
			(end -0.7874 0.4064)
			(stroke
				(width 0.1524)
				(type default)
			)
			(layer "F.SilkS")
		)
		(fp_line
			(start -0.67945 -0.305054)
			(end -0.12065 -0.305054)
			(stroke
				(width 0.1)
				(type default)
			)
			(layer "F.Fab")
		)
		(fp_line
			(start -0.67945 0.3048)
			(end -0.67945 -0.305054)
			(stroke
				(width 0.1)
				(type default)
			)
			(layer "F.Fab")
		)
		(fp_line
			(start -0.12065 -0.305054)
			(end -0.12065 -0.2794)
			(stroke
				(width 0.1)
				(type default)
			)
			(layer "F.Fab")
		)
		(fp_line
			(start -0.12065 -0.2794)
			(end 0.12065 -0.2794)
			(stroke
				(width 0.1)
				(type default)
			)
			(layer "F.Fab")
		)
		(fp_line
			(start -0.12065 0.2794)
			(end -0.12065 0.3048)
			(stroke
				(width 0.1)
				(type default)
			)
			(layer "F.Fab")
		)
		(fp_line
			(start -0.12065 0.3048)
			(end -0.67945 0.3048)
			(stroke
				(width 0.1)
				(type default)
			)
			(layer "F.Fab")
		)
		(fp_line
			(start 0.120396 0.2794)
			(end -0.12065 0.2794)
			(stroke
				(width 0.1)
				(type default)
			)
			(layer "F.Fab")
		)
		(fp_line
			(start 0.120396 0.3048)
			(end 0.120396 0.2794)
			(stroke
				(width 0.1)
				(type default)
			)
			(layer "F.Fab")
		)
		(fp_line
			(start 0.12065 -0.3048)
			(end 0.67945 -0.3048)
			(stroke
				(width 0.1)
				(type default)
			)
			(layer "F.Fab")
		)
		(fp_line
			(start 0.12065 -0.2794)
			(end 0.12065 -0.3048)
			(stroke
				(width 0.1)
				(type default)
			)
			(layer "F.Fab")
		)
		(fp_line
			(start 0.67945 -0.3048)
			(end 0.67945 0.3048)
			(stroke
				(width 0.1)
				(type default)
			)
			(layer "F.Fab")
		)
		(fp_line
			(start 0.67945 0.3048)
			(end 0.120396 0.3048)
			(stroke
				(width 0.1)
				(type default)
			)
			(layer "F.Fab")
		)
		(pad "1" smd circle
			(at -0.40005 0)
			(size 0 0)
			(layers "F.Cu" "F.Mask" "F.Paste")
			(net "P3V3_AUX")
		)
		(pad "2" smd circle
			(at 0.40005 0)
			(size 0 0)
			(layers "F.Cu" "F.Mask" "F.Paste")
			(net "PCA9548_PCIE0_ADDR0")
		)
	)
)
